# T6G (Grand Teton) — schematic netlist excerpt (pin names and nets, part order shuffled) for the footprints in the layout excerpt that follows; sources: Cadence DE-HDL packaged netlist, KiCad conversion of 04192023_DAF0TMB3IC0_F0TG_MB_C_brd_V02_OCP.brd

PC6604  Q_CAP  1UF 16V 10% X6S  pkg C0402  page 362 : A = P0V9_RETIMER_CPU0_VCC ; B = GND
R3977  Q_RES  100K 1% CHIP  pkg 0402LF  page 146 : A = P3V3_AUX ; B = P3V3_E1S_FAULT_0

(kicad_pcb
	(version 20260206)
	(generator "pcbnew")
	(generator_version "10.0")
	(general
		(thickness 1.6)
		(legacy_teardrops no)
	)
	(paper "A4")
	(title_block
		(title "04192023_DAF0TMB3IC0_F0TG_MB_C_brd_V02_OCP.brd")
		(comment 1 "Grand Teton / footprints 3610-3612 of 8354")
	)
	(layers
		(0 "F.Cu" signal "TOP")
		(4 "In1.Cu" signal "GND")
		(6 "In2.Cu" signal "IN1")
		(8 "In3.Cu" signal "GND1")
		(10 "In4.Cu" signal "IN2")
		(12 "In5.Cu" signal "GND2")
		(14 "In6.Cu" signal "IN3")
		(16 "In7.Cu" signal "GND3")
		(18 "In8.Cu" signal "VCC")
		(20 "In9.Cu" signal "VCC1")
		(22 "In10.Cu" signal "GND4")
		(24 "In11.Cu" signal "IN4")
		(26 "In12.Cu" signal "GND5")
		(28 "In13.Cu" signal "IN5")
		(30 "In14.Cu" signal "GND6")
		(32 "In15.Cu" signal "IN6")
		(34 "In16.Cu" signal "GND7")
		(2 "B.Cu" signal "BOTTOM")
		(9 "F.Adhes" user "F.Adhesive")
		(11 "B.Adhes" user "B.Adhesive")
		(13 "F.Paste" user "Package Geometry/Pastemask Top")
		(15 "B.Paste" user "Package Geometry/Pastemask Bottom")
		(5 "F.SilkS" user "Ref Des/Silkscreen Top")
		(7 "B.SilkS" user "Ref Des/Silkscreen Bottom")
		(1 "F.Mask" user "Board Geometry/Soldermask Top")
		(3 "B.Mask" user "Board Geometry/Soldermask Bottom")
		(17 "Dwgs.User" user "User.Drawings")
		(19 "Cmts.User" user "User.Comments")
		(21 "Eco1.User" user "User.Eco1")
		(23 "Eco2.User" user "User.Eco2")
		(25 "Edge.Cuts" user "Board Geometry/Outline")
		(27 "Margin" user)
		(31 "F.CrtYd" user "Package Geometry/Place Bound Top")
		(29 "B.CrtYd" user "Package Geometry/Place Bound Bottom")
		(35 "F.Fab" user "Ref Des/Assembly Top")
		(33 "B.Fab" user "Ref Des/Assembly Bottom")
	)
	(footprint ""
		(layer "F.Cu")
		(at 5.985002 -403.945852 180)
		(property "Reference" ""
			(at 0 0 180)
			(layer "F.SilkS")
			(hide yes)
			(effects
				(font
					(size 1.27 1.27)
				)
			)
		)
		(property "Value" ""
			(at 0 0 180)
			(layer "F.Fab")
			(effects
				(font
					(size 1.27 1.27)
				)
			)
		)
		(duplicate_pad_numbers_are_jumpers no)
		(pad "1" smd circle
			(at 0 0 180)
			(size 0.9906 0.9906)
			(layers "F.Cu" "F.Mask" "F.Paste")
			(net "Net_2240")
		)
		(zone
			(layer "F.Cu")
			(hatch none 0.5)
			(connect_pads
				(clearance 0)
			)
			(min_thickness 0.25)
			(keepout
				(tracks not_allowed)
				(vias allowed)
				(pads allowed)
				(copperpour not_allowed)
				(footprints allowed)
			)
			(placement
				(enabled no)
				(sheetname "")
			)
			(fill
				(thermal_gap 0.5)
				(thermal_bridge_width 0.5)
				(island_removal_mode 0)
			)
			(polygon
				(pts
					(arc
						(start 7.610602 -403.945852)
						(mid 4.359402 -403.945852)
						(end 7.610602 -403.945852)
					)
				)
			)
		)
	)
	(footprint ""
		(layer "F.Cu")
		(at 449.443602 -428.10811)
		(property "Reference" "PC6604"
			(at 0 0 0)
			(layer "F.SilkS")
			(hide yes)
			(effects
				(font
					(size 1.27 1.27)
				)
			)
		)
		(property "Value" ""
			(at 0 0 0)
			(layer "F.Fab")
			(effects
				(font
					(size 1.27 1.27)
				)
			)
		)
		(duplicate_pad_numbers_are_jumpers no)
		(fp_line
			(start -0.7874 -0.4064)
			(end 0.7874 -0.4064)
			(stroke
				(width 0.1524)
				(type default)
			)
			(layer "F.SilkS")
		)
		(fp_line
			(start -0.7874 0.4064)
			(end -0.7874 -0.4064)
			(stroke
				(width 0.1524)
				(type default)
			)
			(layer "F.SilkS")
		)
		(fp_line
			(start 0.7874 -0.4064)
			(end 0.7874 0.4064)
			(stroke
				(width 0.1524)
				(type default)
			)
			(layer "F.SilkS")
		)
		(fp_line
			(start 0.7874 0.4064)
			(end -0.7874 0.4064)
			(stroke
				(width 0.1524)
				(type default)
			)
			(layer "F.SilkS")
		)
		(fp_line
			(start -0.67945 -0.305054)
			(end -0.12065 -0.305054)
			(stroke
				(width 0.1)
				(type default)
			)
			(layer "F.Fab")
		)
		(fp_line
			(start -0.67945 0.3048)
			(end -0.67945 -0.305054)
			(stroke
				(width 0.1)
				(type default)
			)
			(layer "F.Fab")
		)
		(fp_line
			(start -0.12065 -0.305054)
			(end -0.12065 -0.2794)
			(stroke
				(width 0.1)
				(type default)
			)
			(layer "F.Fab")
		)
		(fp_line
			(start -0.12065 -0.2794)
			(end 0.12065 -0.2794)
			(stroke
				(width 0.1)
				(type default)
			)
			(layer "F.Fab")
		)
		(fp_line
			(start -0.12065 0.2794)
			(end -0.12065 0.3048)
			(stroke
				(width 0.1)
				(type default)
			)
			(layer "F.Fab")
		)
		(fp_line
			(start -0.12065 0.3048)
			(end -0.67945 0.3048)
			(stroke
				(width 0.1)
				(type default)
			)
			(layer "F.Fab")
		)
		(fp_line
			(start 0.120396 0.2794)
			(end -0.12065 0.2794)
			(stroke
				(width 0.1)
				(type default)
			)
			(layer "F.Fab")
		)
		(fp_line
			(start 0.120396 0.3048)
			(end 0.120396 0.2794)
			(stroke
				(width 0.1)
				(type default)
			)
			(layer "F.Fab")
		)
		(fp_line
			(start 0.12065 -0.3048)
			(end 0.67945 -0.3048)
			(stroke
				(width 0.1)
				(type default)
			)
			(layer "F.Fab")
		)
		(fp_line
			(start 0.12065 -0.2794)
			(end 0.12065 -0.3048)
			(stroke
				(width 0.1)
				(type default)
			)
			(layer "F.Fab")
		)
		(fp_line
			(start 0.67945 -0.3048)
			(end 0.67945 0.3048)
			(stroke
				(width 0.1)
				(type default)
			)
			(layer "F.Fab")
		)
		(fp_line
			(start 0.67945 0.3048)
			(end 0.120396 0.3048)
			(stroke
				(width 0.1)
				(type default)
			)
			(layer "F.Fab")
		)
		(pad "1" smd circle
			(at -0.40005 0)
			(size 0 0)
			(layers "F.Cu" "F.Mask" "F.Paste")
			(net "P0V9_RETIMER_CPU0_VCC")
		)
		(pad "2" smd circle
			(at 0.40005 0)
			(size 0 0)
			(layers "F.Cu" "F.Mask" "F.Paste")
			(net "GND")
		)
	)
	(footprint ""
		(layer "F.Cu")
		(at 225.171762 -71.192898 90)
		(property "Reference" "R3977"
			(at 0 0 90)
			(layer "F.SilkS")
			(hide yes)
			(effects
				(font
					(size 1.27 1.27)
				)
			)
		)
		(property "Value" ""
			(at 0 0 90)
			(layer "F.Fab")
			(effects
				(font
					(size 1.27 1.27)
				)
			)
		)
		(duplicate_pad_numbers_are_jumpers no)
		(fp_line
			(start 0.7874 -0.4064)
			(end 0.7874 0.4064)
			(stroke
				(width 0.1524)
				(type default)
			)
			(layer "F.SilkS")
		)
		(fp_line
			(start -0.7874 -0.4064)
			(end 0.7874 -0.4064)
			(stroke
				(width 0.1524)
				(type default)
			)
			(layer "F.SilkS")
		)
		(fp_line
			(start 0.7874 0.4064)
			(end -0.7874 0.4064)
			(stroke
				(width 0.1524)
				(type default)
			)
			(layer "F.SilkS")
		)
		(fp_line
			(start -0.7874 0.4064)
			(end -0.7874 -0.4064)
			(stroke
				(width 0.1524)
				(type default)
			)
			(layer "F.SilkS")
		)
		(fp_line
			(start -0.12065 -0.305054)
			(end -0.12065 -0.2794)
			(stroke
				(width 0.1)
				(type default)
			)
			(layer "F.Fab")
		)
		(fp_line
			(start -0.67945 -0.305054)
			(end -0.12065 -0.305054)
			(stroke
				(width 0.1)
				(type default)
			)
			(layer "F.Fab")
		)
		(fp_line
			(start 0.67945 -0.3048)
			(end 0.67945 0.3048)
			(stroke
				(width 0.1)
				(type default)
			)
			(layer "F.Fab")
		)
		(fp_line
			(start 0.12065 -0.3048)
			(end 0.67945 -0.3048)
			(stroke
				(width 0.1)
				(type default)
			)
			(layer "F.Fab")
		)
		(fp_line
			(start 0.12065 -0.2794)
			(end 0.12065 -0.3048)
			(stroke
				(width 0.1)
				(type default)
			)
			(layer "F.Fab")
		)
		(fp_line
			(start -0.12065 -0.2794)
			(end 0.12065 -0.2794)
			(stroke
				(width 0.1)
				(type default)
			)
			(layer "F.Fab")
		)
		(fp_line
			(start 0.120396 0.2794)
			(end -0.12065 0.2794)
			(stroke
				(width 0.1)
				(type default)
			)
			(layer "F.Fab")
		)
		(fp_line
			(start -0.12065 0.2794)
			(end -0.12065 0.3048)
			(stroke
				(width 0.1)
				(type default)
			)
			(layer "F.Fab")
		)
		(fp_line
			(start 0.67945 0.3048)
			(end 0.120396 0.3048)
			(stroke
				(width 0.1)
				(type default)
			)
			(layer "F.Fab")
		)
		(fp_line
			(start 0.120396 0.3048)
			(end 0.120396 0.2794)
			(stroke
				(width 0.1)
				(type default)
			)
			(layer "F.Fab")
		)
		(fp_line
			(start -0.12065 0.3048)
			(end -0.67945 0.3048)
			(stroke
				(width 0.1)
				(type default)
			)
			(layer "F.Fab")
		)
		(fp_line
			(start -0.67945 0.3048)
			(end -0.67945 -0.305054)
			(stroke
				(width 0.1)
				(type default)
			)
			(layer "F.Fab")
		)
		(pad "1" smd circle
			(at -0.40005 0 90)
			(size 0 0)
			(layers "F.Cu" "F.Mask" "F.Paste")
			(net "P3V3_AUX")
		)
		(pad "2" smd circle
			(at 0.40005 0 90)
			(size 0 0)
			(layers "F.Cu" "F.Mask" "F.Paste")
			(net "P3V3_E1S_FAULT_0")
		)
	)
)
